(kicad_pcb
	(version 20221018)
	(generator pcbnew)
	(general
    (thickness 1.656)
  )
	(paper "A4")
	(title_block
    (title "SDI-MIPI Bridge")
    (date "2023-08-09")
    (rev "1.3.4")
    (company "Antmicro")
		(comment 9 "footprints 135-144 of 190")
	)
	(layers
    (0 "F.Cu" signal)
    (1 "In1.Cu" power)
    (2 "In2.Cu" power)
    (3 "In3.Cu" signal)
    (4 "In4.Cu" signal)
    (31 "B.Cu" signal)
    (32 "B.Adhes" user "B.Adhesive")
    (33 "F.Adhes" user "F.Adhesive")
    (34 "B.Paste" user)
    (35 "F.Paste" user)
    (36 "B.SilkS" user "B.Silkscreen")
    (37 "F.SilkS" user "F.Silkscreen")
    (38 "B.Mask" user)
    (39 "F.Mask" user)
    (40 "Dwgs.User" user "User.Drawings")
    (41 "Cmts.User" user "User.Comments")
    (42 "Eco1.User" user "User.Eco1")
    (43 "Eco2.User" user "User.Eco2")
    (44 "Edge.Cuts" user)
    (45 "Margin" user)
    (46 "B.CrtYd" user "B.Courtyard")
    (47 "F.CrtYd" user "F.Courtyard")
    (48 "B.Fab" user)
    (49 "F.Fab" user)
  )
	(footprint "sdi-mipi-bridge-footprints:C_0402_1005Metric" (layer "B.Cu")
    (at 143.25 117.19 90)
    (descr "Capacitor SMD 0402")
    (tags "capacitor SMD 0402")
    (property "Author" "Antmicro")
    (property "Dielectric" "")
    (property "License" "Apache-2.0")
    (property "MPN" "0402X104K6R3CT")
    (property "Manufacturer" "Walsin")
    (property "Sheetfile" "sdi-mipi-bridge.kicad_sch")
    (property "Sheetname" "")
    (property "Val" "100n")
    (property "Voltage" "")
    (property "ki_description" " ")
    (attr smd)
    (fp_text reference "C41" (at -8.81 9.15 90) (layer "B.SilkS")
        (effects (font (size 0.7 0.7) (thickness 0.15)) (justify right bottom mirror))
    )
    (fp_text value "C_100n_6V3_0402" (at 0 -1.4 90) (layer "B.Fab") hide
        (effects (font (size 0.7 0.7) (thickness 0.15)) (justify right bottom mirror))
    )
    (fp_text user "Author: Antmicro" (at -0.932 -4.17 90) (layer "B.Fab") hide
        (effects (font (size 0.7 0.7) (thickness 0.15)) (justify right bottom mirror))
    )
    (fp_text user "License: Apache-2.0" (at -0.932 -5.17 90) (layer "B.Fab") hide
        (effects (font (size 0.7 0.7) (thickness 0.15)) (justify right bottom mirror))
    )
    (fp_text user "${REFERENCE}" (at -0.932 -3.168 90) (layer "B.Fab") hide
        (effects (font (size 0.7 0.7) (thickness 0.15)) (justify right bottom mirror))
    )
    (fp_rect (start -0.94 0.47) (end 0.94 -0.47)
      (stroke (width 0.05) (type solid)) (fill none) (layer "B.CrtYd"))
    (fp_rect (start -0.499 0.249) (end 0.499 -0.249)
      (stroke (width 0.15) (type solid)) (fill none) (layer "B.Fab"))
    (pad "1" smd roundrect (at -0.484 0 90) (size 0.59 0.64) (layers "B.Cu" "B.Paste" "B.Mask") (roundrect_rratio 0.25)
      (net 1 "GNDREF") (pintype "passive"))
    (pad "2" smd roundrect (at 0.484 0 90) (size 0.59 0.64) (layers "B.Cu" "B.Paste" "B.Mask") (roundrect_rratio 0.25)
      (net 79 "VCC_IO") (pintype "passive"))
  )
	(footprint "sdi-mipi-bridge-footprints:C_0402_1005Metric" (layer "B.Cu")
    (at 143.25 114.75 90)
    (descr "Capacitor SMD 0402")
    (tags "capacitor SMD 0402")
    (property "Author" "Antmicro")
    (property "Dielectric" "")
    (property "License" "Apache-2.0")
    (property "MPN" "0402X104K6R3CT")
    (property "Manufacturer" "Walsin")
    (property "Sheetfile" "sdi-mipi-bridge.kicad_sch")
    (property "Sheetname" "")
    (property "Val" "100n")
    (property "Voltage" "")
    (property "ki_description" " ")
    (attr smd)
    (fp_text reference "C46" (at -9.05 9.15 90) (layer "B.SilkS")
        (effects (font (size 0.7 0.7) (thickness 0.15)) (justify right bottom mirror))
    )
    (fp_text value "C_100n_6V3_0402" (at 0 -1.4 90) (layer "B.Fab") hide
        (effects (font (size 0.7 0.7) (thickness 0.15)) (justify right bottom mirror))
    )
    (fp_text user "${REFERENCE}" (at -0.932 -3.168 90) (layer "B.Fab") hide
        (effects (font (size 0.7 0.7) (thickness 0.15)) (justify right bottom mirror))
    )
    (fp_text user "Author: Antmicro" (at -0.932 -4.17 90) (layer "B.Fab") hide
        (effects (font (size 0.7 0.7) (thickness 0.15)) (justify right bottom mirror))
    )
    (fp_text user "License: Apache-2.0" (at -0.932 -5.17 90) (layer "B.Fab") hide
        (effects (font (size 0.7 0.7) (thickness 0.15)) (justify right bottom mirror))
    )
    (fp_rect (start -0.94 0.47) (end 0.94 -0.47)
      (stroke (width 0.05) (type solid)) (fill none) (layer "B.CrtYd"))
    (fp_rect (start -0.499 0.249) (end 0.499 -0.249)
      (stroke (width 0.15) (type solid)) (fill none) (layer "B.Fab"))
    (pad "1" smd roundrect (at -0.484 0 90) (size 0.59 0.64) (layers "B.Cu" "B.Paste" "B.Mask") (roundrect_rratio 0.25)
      (net 1 "GNDREF") (pintype "passive"))
    (pad "2" smd roundrect (at 0.484 0 90) (size 0.59 0.64) (layers "B.Cu" "B.Paste" "B.Mask") (roundrect_rratio 0.25)
      (net 79 "VCC_IO") (pintype "passive"))
  )
	(footprint "sdi-mipi-bridge-footprints:C_0402_1005Metric" (layer "B.Cu")
    (at 146.41 113.49 180)
    (descr "Capacitor SMD 0402")
    (tags "capacitor SMD 0402")
    (property "Author" "Antmicro")
    (property "Dielectric" "")
    (property "License" "Apache-2.0")
    (property "MPN" "0402X104K6R3CT")
    (property "Manufacturer" "Walsin")
    (property "Sheetfile" "sdi-mipi-bridge.kicad_sch")
    (property "Sheetname" "")
    (property "Val" "100n")
    (property "Voltage" "")
    (property "ki_description" " ")
    (attr smd)
    (fp_text reference "C57" (at -9.99 -8.11) (layer "B.SilkS")
        (effects (font (size 0.7 0.7) (thickness 0.15)) (justify left bottom mirror))
    )
    (fp_text value "C_100n_6V3_0402" (at 0 -1.4) (layer "B.Fab") hide
        (effects (font (size 0.7 0.7) (thickness 0.15)) (justify left bottom mirror))
    )
    (fp_text user "${REFERENCE}" (at -0.932 -3.168) (layer "B.Fab") hide
        (effects (font (size 0.7 0.7) (thickness 0.15)) (justify left bottom mirror))
    )
    (fp_text user "License: Apache-2.0" (at -0.932 -5.17) (layer "B.Fab") hide
        (effects (font (size 0.7 0.7) (thickness 0.15)) (justify left bottom mirror))
    )
    (fp_text user "Author: Antmicro" (at -0.932 -4.17) (layer "B.Fab") hide
        (effects (font (size 0.7 0.7) (thickness 0.15)) (justify left bottom mirror))
    )
    (fp_rect (start -0.94 0.47) (end 0.94 -0.47)
      (stroke (width 0.05) (type solid)) (fill none) (layer "B.CrtYd"))
    (fp_rect (start -0.499 0.249) (end 0.499 -0.249)
      (stroke (width 0.15) (type solid)) (fill none) (layer "B.Fab"))
    (pad "1" smd roundrect (at -0.484 0 180) (size 0.59 0.64) (layers "B.Cu" "B.Paste" "B.Mask") (roundrect_rratio 0.25)
      (net 1 "GNDREF") (pintype "passive"))
    (pad "2" smd roundrect (at 0.484 0 180) (size 0.59 0.64) (layers "B.Cu" "B.Paste" "B.Mask") (roundrect_rratio 0.25)
      (net 79 "VCC_IO") (pintype "passive"))
  )
	(footprint "sdi-mipi-bridge-footprints:C_0402_1005Metric" (layer "B.Cu")
    (at 148.095 108 -90)
    (descr "Capacitor SMD 0402")
    (tags "capacitor SMD 0402")
    (property "Author" "Antmicro")
    (property "Dielectric" "")
    (property "License" "Apache-2.0")
    (property "MPN" "0402X104K6R3CT")
    (property "Manufacturer" "Walsin")
    (property "Sheetfile" "sdi-mipi-bridge.kicad_sch")
    (property "Sheetname" "")
    (property "Val" "100n")
    (property "Voltage" "")
    (property "ki_description" " ")
    (attr smd)
    (fp_text reference "C49" (at -3.2 -0.505 90) (layer "B.SilkS")
        (effects (font (size 0.7 0.7) (thickness 0.15)) (justify left bottom mirror))
    )
    (fp_text value "C_100n_6V3_0402" (at 0 -1.4 90) (layer "B.Fab") hide
        (effects (font (size 0.7 0.7) (thickness 0.15)) (justify left bottom mirror))
    )
    (fp_text user "License: Apache-2.0" (at -0.932 -5.17 90) (layer "B.Fab") hide
        (effects (font (size 0.7 0.7) (thickness 0.15)) (justify left bottom mirror))
    )
    (fp_text user "${REFERENCE}" (at -0.932 -3.168 90) (layer "B.Fab") hide
        (effects (font (size 0.7 0.7) (thickness 0.15)) (justify left bottom mirror))
    )
    (fp_text user "Author: Antmicro" (at -0.932 -4.17 90) (layer "B.Fab") hide
        (effects (font (size 0.7 0.7) (thickness 0.15)) (justify left bottom mirror))
    )
    (fp_rect (start -0.94 0.47) (end 0.94 -0.47)
      (stroke (width 0.05) (type solid)) (fill none) (layer "B.CrtYd"))
    (fp_rect (start -0.499 0.249) (end 0.499 -0.249)
      (stroke (width 0.15) (type solid)) (fill none) (layer "B.Fab"))
    (pad "1" smd roundrect (at -0.484 0 270) (size 0.59 0.64) (layers "B.Cu" "B.Paste" "B.Mask") (roundrect_rratio 0.25)
      (net 58 "/GNDPLL_DPHY") (pintype "passive"))
    (pad "2" smd roundrect (at 0.484 0 270) (size 0.59 0.64) (layers "B.Cu" "B.Paste" "B.Mask") (roundrect_rratio 0.25)
      (net 77 "VCCA_DPHY") (pintype "passive"))
  )
	(footprint "sdi-mipi-bridge-footprints:C_0402_1005Metric" (layer "B.Cu")
    (at 147.96 114.93 90)
    (descr "Capacitor SMD 0402")
    (tags "capacitor SMD 0402")
    (property "Author" "Antmicro")
    (property "Dielectric" "")
    (property "License" "Apache-2.0")
    (property "MPN" "0402X104K6R3CT")
    (property "Manufacturer" "Walsin")
    (property "Sheetfile" "sdi-mipi-bridge.kicad_sch")
    (property "Sheetname" "")
    (property "Val" "100n")
    (property "Voltage" "")
    (property "ki_description" " ")
    (attr smd)
    (fp_text reference "C40" (at -6.67 9.24 90) (layer "B.SilkS")
        (effects (font (size 0.7 0.7) (thickness 0.15)) (justify left bottom mirror))
    )
    (fp_text value "C_100n_6V3_0402" (at 0 -1.4 90) (layer "B.Fab") hide
        (effects (font (size 0.7 0.7) (thickness 0.15)) (justify right bottom mirror))
    )
    (fp_text user "Author: Antmicro" (at -0.932 -4.17 90) (layer "B.Fab") hide
        (effects (font (size 0.7 0.7) (thickness 0.15)) (justify right bottom mirror))
    )
    (fp_text user "License: Apache-2.0" (at -0.932 -5.17 90) (layer "B.Fab") hide
        (effects (font (size 0.7 0.7) (thickness 0.15)) (justify right bottom mirror))
    )
    (fp_text user "${REFERENCE}" (at -0.932 -3.168 90) (layer "B.Fab") hide
        (effects (font (size 0.7 0.7) (thickness 0.15)) (justify right bottom mirror))
    )
    (fp_rect (start -0.94 0.47) (end 0.94 -0.47)
      (stroke (width 0.05) (type solid)) (fill none) (layer "B.CrtYd"))
    (fp_rect (start -0.499 0.249) (end 0.499 -0.249)
      (stroke (width 0.15) (type solid)) (fill none) (layer "B.Fab"))
    (pad "1" smd roundrect (at -0.484 0 90) (size 0.59 0.64) (layers "B.Cu" "B.Paste" "B.Mask") (roundrect_rratio 0.25)
      (net 1 "GNDREF") (pintype "passive"))
    (pad "2" smd roundrect (at 0.484 0 90) (size 0.59 0.64) (layers "B.Cu" "B.Paste" "B.Mask") (roundrect_rratio 0.25)
      (net 77 "VCCA_DPHY") (pintype "passive"))
  )
	(footprint "sdi-mipi-bridge-footprints:C_0402_1005Metric" (layer "B.Cu")
    (at 147.97 116.91 -90)
    (descr "Capacitor SMD 0402")
    (tags "capacitor SMD 0402")
    (property "Author" "Antmicro")
    (property "Dielectric" "")
    (property "License" "Apache-2.0")
    (property "MPN" "0402X104K6R3CT")
    (property "Manufacturer" "Walsin")
    (property "Sheetfile" "sdi-mipi-bridge.kicad_sch")
    (property "Sheetname" "")
    (property "Val" "100n")
    (property "Voltage" "")
    (property "ki_description" " ")
    (attr smd)
    (fp_text reference "C53" (at 6.69 -9.23 90) (layer "B.SilkS")
        (effects (font (size 0.7 0.7) (thickness 0.15)) (justify left bottom mirror))
    )
    (fp_text value "C_100n_6V3_0402" (at 0 -1.4 90) (layer "B.Fab") hide
        (effects (font (size 0.7 0.7) (thickness 0.15)) (justify left bottom mirror))
    )
    (fp_text user "${REFERENCE}" (at -0.932 -3.168 90) (layer "B.Fab") hide
        (effects (font (size 0.7 0.7) (thickness 0.15)) (justify left bottom mirror))
    )
    (fp_text user "License: Apache-2.0" (at -0.932 -5.17 90) (layer "B.Fab") hide
        (effects (font (size 0.7 0.7) (thickness 0.15)) (justify left bottom mirror))
    )
    (fp_text user "Author: Antmicro" (at -0.932 -4.17 90) (layer "B.Fab") hide
        (effects (font (size 0.7 0.7) (thickness 0.15)) (justify left bottom mirror))
    )
    (fp_rect (start -0.94 0.47) (end 0.94 -0.47)
      (stroke (width 0.05) (type solid)) (fill none) (layer "B.CrtYd"))
    (fp_rect (start -0.499 0.249) (end 0.499 -0.249)
      (stroke (width 0.15) (type solid)) (fill none) (layer "B.Fab"))
    (pad "1" smd roundrect (at -0.484 0 270) (size 0.59 0.64) (layers "B.Cu" "B.Paste" "B.Mask") (roundrect_rratio 0.25)
      (net 58 "/GNDPLL_DPHY") (pintype "passive"))
    (pad "2" smd roundrect (at 0.484 0 270) (size 0.59 0.64) (layers "B.Cu" "B.Paste" "B.Mask") (roundrect_rratio 0.25)
      (net 77 "VCCA_DPHY") (pintype "passive"))
  )
	(footprint "sdi-mipi-bridge-footprints:C_0402_1005Metric" (layer "B.Cu")
    (at 146.4 112.46)
    (descr "Capacitor SMD 0402")
    (tags "capacitor SMD 0402")
    (property "Author" "Antmicro")
    (property "Dielectric" "")
    (property "License" "Apache-2.0")
    (property "MPN" "0402X104K6R3CT")
    (property "Manufacturer" "Walsin")
    (property "Sheetfile" "sdi-mipi-bridge.kicad_sch")
    (property "Sheetname" "")
    (property "Val" "100n")
    (property "Voltage" "")
    (property "ki_description" " ")
    (attr smd)
    (fp_text reference "C44" (at 10 8.14) (layer "B.SilkS")
        (effects (font (size 0.7 0.7) (thickness 0.15)) (justify left bottom mirror))
    )
    (fp_text value "C_100n_6V3_0402" (at 0 -1.4) (layer "B.Fab") hide
        (effects (font (size 0.7 0.7) (thickness 0.15)) (justify right bottom mirror))
    )
    (fp_text user "Author: Antmicro" (at -0.932 -4.17) (layer "B.Fab") hide
        (effects (font (size 0.7 0.7) (thickness 0.15)) (justify right bottom mirror))
    )
    (fp_text user "License: Apache-2.0" (at -0.932 -5.17) (layer "B.Fab") hide
        (effects (font (size 0.7 0.7) (thickness 0.15)) (justify right bottom mirror))
    )
    (fp_text user "${REFERENCE}" (at -0.932 -3.168) (layer "B.Fab") hide
        (effects (font (size 0.7 0.7) (thickness 0.15)) (justify right bottom mirror))
    )
    (fp_rect (start -0.94 0.47) (end 0.94 -0.47)
      (stroke (width 0.05) (type solid)) (fill none) (layer "B.CrtYd"))
    (fp_rect (start -0.499 0.249) (end 0.499 -0.249)
      (stroke (width 0.15) (type solid)) (fill none) (layer "B.Fab"))
    (pad "1" smd roundrect (at -0.484 0) (size 0.59 0.64) (layers "B.Cu" "B.Paste" "B.Mask") (roundrect_rratio 0.25)
      (net 1 "GNDREF") (pintype "passive"))
    (pad "2" smd roundrect (at 0.484 0) (size 0.59 0.64) (layers "B.Cu" "B.Paste" "B.Mask") (roundrect_rratio 0.25)
      (net 77 "VCCA_DPHY") (pintype "passive"))
  )
	(footprint "sdi-mipi-bridge-footprints:R_0402_1005Metric" (layer "B.Cu")
    (at 150.205 110)
    (descr "Resistor SMD 0402")
    (tags "resistor SMD 0402")
    (property "Author" "Antmicro")
    (property "Current" "1A")
    (property "License" "Apache-2.0")
    (property "MPN" "ERJ2GE0R00X")
    (property "Manufacturer" "Panasonic")
    (property "Sheetfile" "sdi-mipi-bridge.kicad_sch")
    (property "Sheetname" "")
    (property "Tolerance" "")
    (property "Val" "0R")
    (property "ki_description" "0R resistor in 0402 package with unspecified tolerance")
    (attr smd)
    (fp_text reference "R67" (at 0.995 -0.6 180) (layer "B.SilkS")
        (effects (font (size 0.7 0.7) (thickness 0.15)) (justify left bottom mirror))
    )
    (fp_text value "R_0R_0402" (at 0 -1.4 180) (layer "B.Fab") hide
        (effects (font (size 0.7 0.7) (thickness 0.15)) (justify left bottom mirror))
    )
    (fp_text user "${REFERENCE}" (at -0.95 -3.168 180) (layer "B.Fab") hide
        (effects (font (size 0.7 0.7) (thickness 0.15)) (justify left bottom mirror))
    )
    (fp_text user "License: Apache-2.0" (at -0.95 -5.169 180) (layer "B.Fab") hide
        (effects (font (size 0.7 0.7) (thickness 0.15)) (justify left bottom mirror))
    )
    (fp_text user "Author: Antmicro" (at -0.95 -4.169 180) (layer "B.Fab") hide
        (effects (font (size 0.7 0.7) (thickness 0.15)) (justify left bottom mirror))
    )
    (fp_rect (start -0.93 0.47) (end 0.93 -0.47)
      (stroke (width 0.05) (type solid)) (fill none) (layer "B.CrtYd"))
    (fp_rect (start -0.5 0.25) (end 0.5 -0.25)
      (stroke (width 0.15) (type solid)) (fill none) (layer "B.Fab"))
    (pad "1" smd roundrect (at -0.485 0) (size 0.59 0.64) (layers "B.Cu" "B.Paste" "B.Mask") (roundrect_rratio 0.25)
      (net 6 "+3V3") (pintype "passive"))
    (pad "2" smd roundrect (at 0.485 0) (size 0.59 0.64) (layers "B.Cu" "B.Paste" "B.Mask") (roundrect_rratio 0.25)
      (net 98 "Net-(R67-Pad2)") (pintype "passive"))
  )
	(footprint "sdi-mipi-bridge-footprints:R_0402_1005Metric" (layer "B.Cu")
    (at 144.99 105.475 -90)
    (descr "Resistor SMD 0402")
    (tags "resistor SMD 0402")
    (property "Author" "Antmicro")
    (property "Current" "1A")
    (property "License" "Apache-2.0")
    (property "MPN" "ERJ2GE0R00X")
    (property "Manufacturer" "Panasonic")
    (property "Sheetfile" "sdi-mipi-bridge.kicad_sch")
    (property "Sheetname" "")
    (property "Tolerance" "")
    (property "Val" "0R")
    (property "ki_description" "0R resistor in 0402 package with unspecified tolerance")
    (attr smd)
    (fp_text reference "R69" (at -3.075 -0.41 90) (layer "B.SilkS")
        (effects (font (size 0.7 0.7) (thickness 0.15)) (justify left bottom mirror))
    )
    (fp_text value "R_0R_0402" (at 0 -1.4 90) (layer "B.Fab") hide
        (effects (font (size 0.7 0.7) (thickness 0.15)) (justify left bottom mirror))
    )
    (fp_text user "Author: Antmicro" (at -0.95 -4.169 90) (layer "B.Fab") hide
        (effects (font (size 0.7 0.7) (thickness 0.15)) (justify left bottom mirror))
    )
    (fp_text user "${REFERENCE}" (at -0.95 -3.168 90) (layer "B.Fab") hide
        (effects (font (size 0.7 0.7) (thickness 0.15)) (justify left bottom mirror))
    )
    (fp_text user "License: Apache-2.0" (at -0.95 -5.169 90) (layer "B.Fab") hide
        (effects (font (size 0.7 0.7) (thickness 0.15)) (justify left bottom mirror))
    )
    (fp_rect (start -0.93 0.47) (end 0.93 -0.47)
      (stroke (width 0.05) (type solid)) (fill none) (layer "B.CrtYd"))
    (fp_rect (start -0.5 0.25) (end 0.5 -0.25)
      (stroke (width 0.15) (type solid)) (fill none) (layer "B.Fab"))
    (pad "1" smd roundrect (at -0.485 0 270) (size 0.59 0.64) (layers "B.Cu" "B.Paste" "B.Mask") (roundrect_rratio 0.25)
      (net 1 "GNDREF") (pintype "passive"))
    (pad "2" smd roundrect (at 0.485 0 270) (size 0.59 0.64) (layers "B.Cu" "B.Paste" "B.Mask") (roundrect_rratio 0.25)
      (net 59 "/GNDGPLL") (pintype "passive"))
  )
	(footprint "sdi-mipi-bridge-footprints:R_0402_1005Metric" (layer "B.Cu")
    (at 145.99 105.475 -90)
    (descr "Resistor SMD 0402")
    (tags "resistor SMD 0402")
    (property "Author" "Antmicro")
    (property "Current" "1A")
    (property "License" "Apache-2.0")
    (property "MPN" "ERJ2GE0R00X")
    (property "Manufacturer" "Panasonic")
    (property "Sheetfile" "sdi-mipi-bridge.kicad_sch")
    (property "Sheetname" "")
    (property "Tolerance" "")
    (property "Val" "0R")
    (property "ki_description" "0R resistor in 0402 package with unspecified tolerance")
    (attr smd)
    (fp_text reference "R70" (at -3.075 -0.41 90) (layer "B.SilkS")
        (effects (font (size 0.7 0.7) (thickness 0.15)) (justify left bottom mirror))
    )
    (fp_text value "R_0R_0402" (at 0 -1.4 90) (layer "B.Fab") hide
        (effects (font (size 0.7 0.7) (thickness 0.15)) (justify left bottom mirror))
    )
    (fp_text user "Author: Antmicro" (at -0.95 -4.169 90) (layer "B.Fab") hide
        (effects (font (size 0.7 0.7) (thickness 0.15)) (justify left bottom mirror))
    )
    (fp_text user "License: Apache-2.0" (at -0.95 -5.169 90) (layer "B.Fab") hide
        (effects (font (size 0.7 0.7) (thickness 0.15)) (justify left bottom mirror))
    )
    (fp_text user "${REFERENCE}" (at -0.95 -3.168 90) (layer "B.Fab") hide
        (effects (font (size 0.7 0.7) (thickness 0.15)) (justify left bottom mirror))
    )
    (fp_rect (start -0.93 0.47) (end 0.93 -0.47)
      (stroke (width 0.05) (type solid)) (fill none) (layer "B.CrtYd"))
    (fp_rect (start -0.5 0.25) (end 0.5 -0.25)
      (stroke (width 0.15) (type solid)) (fill none) (layer "B.Fab"))
    (pad "1" smd roundrect (at -0.485 0 270) (size 0.59 0.64) (layers "B.Cu" "B.Paste" "B.Mask") (roundrect_rratio 0.25)
      (net 1 "GNDREF") (pintype "passive"))
    (pad "2" smd roundrect (at 0.485 0 270) (size 0.59 0.64) (layers "B.Cu" "B.Paste" "B.Mask") (roundrect_rratio 0.25)
      (net 58 "/GNDPLL_DPHY") (pintype "passive"))
  )
)
